# TIMECARD (Time Appliance Project (Time Card)) — schematic netlist excerpt (pin names and nets, part order shuffled) for the footprints in the layout excerpt that follows; sources: Cadence DE-HDL packaged netlist, KiCad conversion of R4006-B0001-02_R01.brd

TP33  TP_PIONT  pkg TP010CT020B030_PTH  page 25 : \1\ = SMA2_SIG_OUT_BF_EN_N
R79  RESISTOR  33OHM 1%  pkg SMC_0402R_H016  page 20 : \1\ = FPGA_IN_BNO080_INT_N ; \2\ = R_BNO080_INT_N
R25  RESISTOR  4.7KOHM 1%  pkg SMC_0402R_H016  page 9 : \1\ = XP3R3V_FPGA ; \2\ = UNNAMED_3_G2201019801_I100_EN

(kicad_pcb
	(version 20260206)
	(generator "pcbnew")
	(generator_version "10.0")
	(general
		(thickness 1.6)
		(legacy_teardrops no)
	)
	(paper "A4")
	(title_block
		(title "timecard-production-celestica-r4006 — R4006-B0001-02_R01.brd")
		(comment 1 "Time Appliance Project (Time Card) / footprints 372-374 of 1113")
	)
	(layers
		(0 "F.Cu" signal "TOP")
		(4 "In1.Cu" signal "L02_GND1")
		(6 "In2.Cu" signal "L03_SIG1")
		(8 "In3.Cu" signal "L04_GND2")
		(10 "In4.Cu" signal "L05_VCC1")
		(12 "In5.Cu" signal "L06_VCC2")
		(14 "In6.Cu" signal "L07_GND3")
		(16 "In7.Cu" signal "L08_SIG2")
		(18 "In8.Cu" signal "L09_GND4")
		(2 "B.Cu" signal "BOTTOM")
		(9 "F.Adhes" user "F.Adhesive")
		(11 "B.Adhes" user "B.Adhesive")
		(13 "F.Paste" user "Package Geometry/Pastemask Top")
		(15 "B.Paste" user "Package Geometry/Pastemask Bottom")
		(5 "F.SilkS" user "Ref Des/Silkscreen Top")
		(7 "B.SilkS" user "Ref Des/Silkscreen Bottom")
		(1 "F.Mask" user "Board Geometry/Soldermask Top")
		(3 "B.Mask" user "Board Geometry/Soldermask Bottom")
		(17 "Dwgs.User" user "User.Drawings")
		(19 "Cmts.User" user "User.Comments")
		(21 "Eco1.User" user "User.Eco1")
		(23 "Eco2.User" user "User.Eco2")
		(25 "Edge.Cuts" user "Board Geometry/Outline")
		(27 "Margin" user)
		(31 "F.CrtYd" user "Package Geometry/Place Bound Top")
		(29 "B.CrtYd" user "Package Geometry/Place Bound Bottom")
		(35 "F.Fab" user "Ref Des/Assembly Top")
		(33 "B.Fab" user "Ref Des/Assembly Bottom")
	)
	(footprint ""
		(layer "F.Cu")
		(at 80.772 -57.2516)
		(property "Reference" "R79"
			(at -10.668 -19.39163 0)
			(unlocked yes)
			(layer "F.SilkS")
			(effects
				(font
					(size 0.7874 0.5842)
					(thickness 0.1524)
				)
			)
		)
		(property "Value" "VAL*"
			(at 0.02032 2.13233 0)
			(unlocked yes)
			(layer "F.Fab")
			(hide yes)
			(effects
				(font
					(size 0.7874 0.5842)
					(thickness 0.1524)
				)
			)
		)
		(property "Tolerance" "TOL*"
			(at 0.044704 3.05435 0)
			(unlocked yes)
			(layer "Cmts.User")
			(hide yes)
			(effects
				(font
					(size 0.7874 0.5842)
					(thickness 0.1524)
				)
			)
		)
		(property "User Part Number" "PARTNUM*"
			(at 0.02032 4.024884 0)
			(unlocked yes)
			(layer "Cmts.User")
			(hide yes)
			(effects
				(font
					(size 0.7874 0.5842)
					(thickness 0.1524)
				)
			)
		)
		(property "Device Type" "RESISTOR-G155-133R0-01,33OHM,1%"
			(at 0.008382 1.210564 0)
			(unlocked yes)
			(layer "F.Fab")
			(hide yes)
			(effects
				(font
					(size 0.7874 0.5842)
					(thickness 0.1524)
				)
			)
		)
		(duplicate_pad_numbers_are_jumpers no)
		(fp_line
			(start -1.143 -0.5588)
			(end -1.143 0.5588)
			(stroke
				(width 0.1)
				(type default)
			)
			(layer "F.SilkS")
		)
		(fp_line
			(start -1.143 0.5588)
			(end 1.143 0.5588)
			(stroke
				(width 0.1)
				(type default)
			)
			(layer "F.SilkS")
		)
		(fp_line
			(start 1.143 -0.5588)
			(end -1.143 -0.5588)
			(stroke
				(width 0.1)
				(type default)
			)
			(layer "F.SilkS")
		)
		(fp_line
			(start 1.143 0.5588)
			(end 1.143 -0.5588)
			(stroke
				(width 0.1)
				(type default)
			)
			(layer "F.SilkS")
		)
		(fp_rect
			(start -1.143 0.5588)
			(end 1.143 -0.5588)
			(stroke
				(width 0)
				(type default)
			)
			(fill no)
			(layer "F.CrtYd")
		)
		(fp_line
			(start -0.508 -0.3048)
			(end -0.508 0.3048)
			(stroke
				(width 0.1)
				(type default)
			)
			(layer "F.Fab")
		)
		(fp_line
			(start -0.508 0.3048)
			(end 0.508 0.3048)
			(stroke
				(width 0.1)
				(type default)
			)
			(layer "F.Fab")
		)
		(fp_line
			(start 0.508 -0.3048)
			(end -0.508 -0.3048)
			(stroke
				(width 0.1)
				(type default)
			)
			(layer "F.Fab")
		)
		(fp_line
			(start 0.508 0.3048)
			(end 0.508 -0.3048)
			(stroke
				(width 0.1)
				(type default)
			)
			(layer "F.Fab")
		)
		(pad "1" smd rect
			(at -0.5334 0)
			(size 0.7112 0.6096)
			(layers "F.Cu" "F.Mask" "F.Paste")
			(net "FPGA_IN_BNO080_INT_N")
		)
		(pad "2" smd rect
			(at 0.5334 0)
			(size 0.7112 0.6096)
			(layers "F.Cu" "F.Mask" "F.Paste")
			(net "R_BNO080_INT_N")
		)
		(zone
			(layer "F.Cu")
			(hatch none 0.5)
			(connect_pads
				(clearance 0)
			)
			(min_thickness 0.25)
			(keepout
				(tracks allowed)
				(vias not_allowed)
				(pads allowed)
				(copperpour not_allowed)
				(footprints allowed)
			)
			(placement
				(enabled no)
				(sheetname "")
			)
			(fill
				(thermal_gap 0.5)
				(thermal_bridge_width 0.5)
				(island_removal_mode 0)
			)
			(polygon
				(pts
					(xy 80.6958 -56.9468) (xy 80.8482 -56.9468) (xy 80.8482 -57.5564) (xy 80.6958 -57.5564)
				)
			)
		)
	)
	(footprint ""
		(layer "F.Cu")
		(at 15.748 -50.673)
		(property "Reference" "TP33"
			(at 1.18237 3.3782 90)
			(unlocked yes)
			(layer "F.SilkS")
			(effects
				(font
					(size 0.7874 0.5842)
					(thickness 0.1524)
				)
				(justify left)
			)
		)
		(property "Value" ""
			(at 0 0 0)
			(layer "F.Fab")
			(effects
				(font
					(size 1.27 1.27)
				)
			)
		)
		(property "Device Type" "TP_PIONT-TP010CT020B030_PTH-TPA"
			(at -1.341882 0.996696 0)
			(unlocked yes)
			(layer "F.Fab")
			(hide yes)
			(effects
				(font
					(size 0.7874 0.5842)
					(thickness 0.000001)
				)
				(justify left)
			)
		)
		(duplicate_pad_numbers_are_jumpers no)
		(fp_poly
			(pts
				(arc
					(start 0.889 0)
					(mid -0.889 0)
					(end 0.889 0)
				)
			)
			(stroke
				(width 0)
				(type default)
			)
			(fill no)
			(layer "B.CrtYd")
		)
		(fp_poly
			(pts
				(arc
					(start 0.889 0)
					(mid -0.889 0)
					(end 0.889 0)
				)
			)
			(stroke
				(width 0)
				(type default)
			)
			(fill no)
			(layer "F.CrtYd")
		)
		(pad "1" thru_hole circle
			(at 0 0)
			(size 0.508 0.508)
			(drill 0.254)
			(layers "*.Cu" "*.Mask")
			(remove_unused_layers no)
			(net "SMA2_SIG_OUT_BF_EN_N")
			(clearance 0.1016)
			(padstack
				(mode front_inner_back)
				(layer "Inner"
					(shape circle)
					(size 0.508 0.508)
					(clearance 0.1016)
				)
				(layer "B.Cu"
					(shape circle)
					(size 0.762 0.762)
					(clearance -0.0254)
				)
			)
		)
	)
	(footprint ""
		(layer "F.Cu")
		(at 52.01158 -15.5194 -90)
		(property "Reference" "R25"
			(at -3.0226 -0.22479 90)
			(unlocked yes)
			(layer "F.SilkS")
			(effects
				(font
					(size 0.7874 0.5842)
					(thickness 0.1524)
				)
			)
		)
		(property "Value" "VAL*"
			(at 0.02032 2.13233 270)
			(unlocked yes)
			(layer "F.Fab")
			(hide yes)
			(effects
				(font
					(size 0.7874 0.5842)
					(thickness 0.1524)
				)
			)
		)
		(property "Tolerance" "TOL*"
			(at 0.044704 3.05435 270)
			(unlocked yes)
			(layer "Cmts.User")
			(hide yes)
			(effects
				(font
					(size 0.7874 0.5842)
					(thickness 0.1524)
				)
			)
		)
		(property "User Part Number" "PARTNUM*"
			(at 0.02032 4.024884 270)
			(unlocked yes)
			(layer "Cmts.User")
			(hide yes)
			(effects
				(font
					(size 0.7874 0.5842)
					(thickness 0.1524)
				)
			)
		)
		(property "Device Type" "RESISTOR-G155-14701-01,4.7KOHMA"
			(at 0.008382 1.210564 270)
			(unlocked yes)
			(layer "F.Fab")
			(hide yes)
			(effects
				(font
					(size 0.7874 0.5842)
					(thickness 0.1524)
				)
			)
		)
		(duplicate_pad_numbers_are_jumpers no)
		(fp_line
			(start -1.143 0.5588)
			(end 1.143 0.5588)
			(stroke
				(width 0.1)
				(type default)
			)
			(layer "F.SilkS")
		)
		(fp_line
			(start 1.143 0.5588)
			(end 1.143 -0.5588)
			(stroke
				(width 0.1)
				(type default)
			)
			(layer "F.SilkS")
		)
		(fp_line
			(start -1.143 -0.5588)
			(end -1.143 0.5588)
			(stroke
				(width 0.1)
				(type default)
			)
			(layer "F.SilkS")
		)
		(fp_line
			(start 1.143 -0.5588)
			(end -1.143 -0.5588)
			(stroke
				(width 0.1)
				(type default)
			)
			(layer "F.SilkS")
		)
		(fp_rect
			(start 1.143 0.5588)
			(end -1.143 -0.5588)
			(stroke
				(width 0)
				(type default)
			)
			(fill no)
			(layer "F.CrtYd")
		)
		(fp_line
			(start -0.508 0.3048)
			(end 0.508 0.3048)
			(stroke
				(width 0.1)
				(type default)
			)
			(layer "F.Fab")
		)
		(fp_line
			(start 0.508 0.3048)
			(end 0.508 -0.3048)
			(stroke
				(width 0.1)
				(type default)
			)
			(layer "F.Fab")
		)
		(fp_line
			(start -0.508 -0.3048)
			(end -0.508 0.3048)
			(stroke
				(width 0.1)
				(type default)
			)
			(layer "F.Fab")
		)
		(fp_line
			(start 0.508 -0.3048)
			(end -0.508 -0.3048)
			(stroke
				(width 0.1)
				(type default)
			)
			(layer "F.Fab")
		)
		(pad "1" smd rect
			(at -0.5334 0 270)
			(size 0.7112 0.6096)
			(layers "F.Cu" "F.Mask" "F.Paste")
			(net "XP3R3V_FPGA")
		)
		(pad "2" smd rect
			(at 0.5334 0 270)
			(size 0.7112 0.6096)
			(layers "F.Cu" "F.Mask" "F.Paste")
			(net "UNNAMED_3_G2201019801_I100_EN")
		)
		(zone
			(layer "F.Cu")
			(hatch none 0.5)
			(connect_pads
				(clearance 0)
			)
			(min_thickness 0.25)
			(keepout
				(tracks allowed)
				(vias not_allowed)
				(pads allowed)
				(copperpour not_allowed)
				(footprints allowed)
			)
			(placement
				(enabled no)
				(sheetname "")
			)
			(fill
				(thermal_gap 0.5)
				(thermal_bridge_width 0.5)
				(island_removal_mode 0)
			)
			(polygon
				(pts
					(xy 51.70678 -15.4432) (xy 52.31638 -15.4432) (xy 52.31638 -15.5956) (xy 51.70678 -15.5956)
				)
			)
		)
	)
)
